# PolarFire SoM — KiCad project settings (.kicad_pro: net classes, design rules, text variables)
{
  "board": {
    "3dviewports": [],
    "design_settings": {
      "defaults": {
        "apply_defaults_to_fp_fields": false,
        "apply_defaults_to_fp_shapes": false,
        "apply_defaults_to_fp_text": false,
        "board_outline_line_width": 0.1,
        "copper_line_width": 0.2,
        "copper_text_italic": false,
        "copper_text_size_h": 1.5,
        "copper_text_size_v": 1.5,
        "copper_text_thickness": 0.3,
        "copper_text_upright": false,
        "courtyard_line_width": 0.05,
        "dimension_precision": 4,
        "dimension_units": 3,
        "dimensions": {
          "arrow_length": 1270000,
          "extension_offset": 500000,
          "keep_text_aligned": true,
          "suppress_zeroes": false,
          "text_position": 0,
          "units_format": 1
        },
        "fab_line_width": 0.1,
        "fab_text_italic": false,
        "fab_text_size_h": 1.0,
        "fab_text_size_v": 1.0,
        "fab_text_thickness": 0.15,
        "fab_text_upright": false,
        "other_line_width": 0.15,
        "other_text_italic": false,
        "other_text_size_h": 1.0,
        "other_text_size_v": 1.0,
        "other_text_thickness": 0.15,
        "other_text_upright": false,
        "pads": {
          "drill": 0.0,
          "height": 0.48,
          "width": 0.25
        },
        "silk_line_width": 0.15,
        "silk_text_italic": false,
        "silk_text_size_h": 1.0,
        "silk_text_size_v": 1.0,
        "silk_text_thickness": 0.15,
        "silk_text_upright": false,
        "zones": {
          "45_degree_only": false,
          "min_clearance": 0.2
        }
      },
      "diff_pair_dimensions": [
        {
          "gap": 0.0,
          "via_gap": 0.0,
          "width": 0.0
        }
      ],
      "drc_exclusions": [],
      "meta": {
        "version": 2
      },
      "rule_severities": {
        "annular_width": "error",
        "clearance": "error",
        "connection_width": "warning",
        "copper_edge_clearance": "error",
        "copper_sliver": "warning",
        "courtyards_overlap": "error",
        "creepage": "error",
        "diff_pair_gap_out_of_range": "ignore",
        "diff_pair_uncoupled_length_too_long": "error",
        "drill_out_of_range": "error",
        "duplicate_footprints": "warning",
        "extra_footprint": "warning",
        "footprint": "error",
        "footprint_filters_mismatch": "warning",
        "footprint_symbol_mismatch": "warning",
        "footprint_type_mismatch": "warning",
        "hole_clearance": "error",
        "hole_near_hole": "error",
        "hole_to_hole": "error",
        "holes_co_located": "error",
        "invalid_outline": "error",
        "isolated_copper": "warning",
        "item_on_disabled_layer": "error",
        "items_not_allowed": "error",
        "length_out_of_range": "error",
        "lib_footprint_issues": "warning",
        "lib_footprint_mismatch": "warning",
        "malformed_courtyard": "error",
        "microvia_drill_out_of_range": "error",
        "mirrored_text_on_front_layer": "warning",
        "missing_courtyard": "warning",
        "missing_footprint": "warning",
        "net_conflict": "warning",
        "nonmirrored_text_on_back_layer": "warning",
        "npth_inside_courtyard": "warning",
        "padstack": "error",
        "pth_inside_courtyard": "warning",
        "shorting_items": "error",
        "silk_edge_clearance": "warning",
        "silk_over_copper": "ignore",
        "silk_overlap": "ignore",
        "skew_out_of_range": "error",
        "solder_mask_bridge": "error",
        "starved_thermal": "error",
        "text_height": "warning",
        "text_on_edge_cuts": "error",
        "text_thickness": "warning",
        "through_hole_pad_without_hole": "error",
        "too_many_vias": "error",
        "track_angle": "error",
        "track_dangling": "warning",
        "track_segment_length": "error",
        "track_width": "error",
        "tracks_crossing": "error",
        "unconnected_items": "error",
        "unresolved_variable": "error",
        "via_dangling": "warning",
        "zones_intersect": "error"
      },
      "rules": {
        "allow_blind_buried_vias": false,
        "allow_microvias": false,
        "max_error": 0.005,
        "min_clearance": 0.09,
        "min_connection": 0.0,
        "min_copper_edge_clearance": 0.3,
        "min_groove_width": 0.0,
        "min_hole_clearance": 0.19,
        "min_hole_to_hole": 0.254,
        "min_microvia_diameter": 0.35,
        "min_microvia_drill": 0.15,
        "min_resolved_spokes": 1,
        "min_silk_clearance": 0.0,
        "min_text_height": 0.65,
        "min_text_thickness": 0.07,
        "min_through_hole_diameter": 0.15,
        "min_track_width": 0.09,
        "min_via_annular_width": 0.1,
        "min_via_diameter": 0.35,
        "solder_mask_clearance": 0.0,
        "solder_mask_min_width": 0.0,
        "solder_mask_to_copper_clearance": 0.0,
        "use_height_for_length_calcs": true
      },
      "teardrop_options": [
        {
          "td_onpthpad": true,
          "td_onroundshapesonly": false,
          "td_onsmdpad": true,
          "td_ontrackend": false,
          "td_onvia": true
        }
      ],
      "teardrop_parameters": [
        {
          "td_allow_use_two_tracks": true,
          "td_curve_segcount": 0,
          "td_height_ratio": 1.0,
          "td_length_ratio": 0.5,
          "td_maxheight": 2.0,
          "td_maxlen": 1.0,
          "td_on_pad_in_zone": false,
          "td_target_name": "td_round_shape",
          "td_width_to_size_filter_ratio": 0.9
        },
        {
          "td_allow_use_two_tracks": true,
          "td_curve_segcount": 0,
          "td_height_ratio": 1.0,
          "td_length_ratio": 0.5,
          "td_maxheight": 2.0,
          "td_maxlen": 1.0,
          "td_on_pad_in_zone": false,
          "td_target_name": "td_rect_shape",
          "td_width_to_size_filter_ratio": 0.9
        },
        {
          "td_allow_use_two_tracks": true,
          "td_curve_segcount": 0,
          "td_height_ratio": 1.0,
          "td_length_ratio": 0.5,
          "td_maxheight": 2.0,
          "td_maxlen": 1.0,
          "td_on_pad_in_zone": false,
          "td_target_name": "td_track_end",
          "td_width_to_size_filter_ratio": 0.9
        }
      ],
      "track_widths": [
        0.0,
        0.09,
        0.1,
        0.11,
        0.125,
        0.15,
        0.2,
        0.256,
        0.4,
        2.0
      ],
      "tuning_pattern_settings": {
        "diff_pair_defaults": {
          "corner_radius_percentage": 80,
          "corner_style": 1,
          "max_amplitude": 1.0,
          "min_amplitude": 0.2,
          "single_sided": false,
          "spacing": 1.0
        },
        "diff_pair_skew_defaults": {
          "corner_radius_percentage": 80,
          "corner_style": 1,
          "max_amplitude": 1.0,
          "min_amplitude": 0.2,
          "single_sided": false,
          "spacing": 0.6
        },
        "single_track_defaults": {
          "corner_radius_percentage": 80,
          "corner_style": 1,
          "max_amplitude": 1.0,
          "min_amplitude": 0.2,
          "single_sided": false,
          "spacing": 0.6
        }
      },
      "via_dimensions": [
        {
          "diameter": 0.0,
          "drill": 0.0
        },
        {
          "diameter": 0.35,
          "drill": 0.15
        }
      ],
      "zones_allow_external_fillets": false,
      "zones_use_no_outline": true
    },
    "ipc2581": {
      "dist": "",
      "distpn": "",
      "internal_id": "",
      "mfg": "",
      "mpn": ""
    },
    "layer_pairs": [],
    "layer_presets": [],
    "viewports": []
  },
  "boards": [],
  "cvpcb": {
    "equivalence_files": []
  },
  "erc": {
    "erc_exclusions": [],
    "meta": {
      "version": 0
    },
    "pin_map": [
      [
        0,
        0,
        0,
        0,
        0,
        0,
        1,
        0,
        0,
        0,
        0,
        2
      ],
      [
        0,
        2,
        0,
        1,
        0,
        0,
        1,
        0,
        2,
        2,
        2,
        2
      ],
      [
        0,
        0,
        0,
        0,
        0,
        0,
        1,
        0,
        1,
        0,
        1,
        2
      ],
      [
        0,
        1,
        0,
        0,
        0,
        0,
        1,
        1,
        2,
        1,
        1,
        2
      ],
      [
        0,
        0,
        0,
        0,
        0,
        0,
        1,
        0,
        0,
        0,
        0,
        2
      ],
      [
        0,
        0,
        0,
        0,
        0,
        0,
        0,
        0,
        0,
        0,
        0,
        2
      ],
      [
        1,
        1,
        1,
        1,
        1,
        0,
        1,
        1,
        1,
        1,
        1,
        2
      ],
      [
        0,
        0,
        0,
        1,
        0,
        0,
        1,
        0,
        0,
        0,
        0,
        2
      ],
      [
        0,
        2,
        1,
        2,
        0,
        0,
        1,
        0,
        2,
        2,
        2,
        2
      ],
      [
        0,
        2,
        0,
        1,
        0,
        0,
        1,
        0,
        2,
        0,
        0,
        2
      ],
      [
        0,
        2,
        1,
        1,
        0,
        0,
        1,
        0,
        2,
        0,
        0,
        2
      ],
      [
        2,
        2,
        2,
        2,
        2,
        2,
        2,
        2,
        2,
        2,
        2,
        2
      ]
    ],
    "rule_severities": {
      "bus_definition_conflict": "error",
      "bus_entry_needed": "error",
      "bus_to_bus_conflict": "error",
      "bus_to_net_conflict": "error",
      "conflicting_netclasses": "error",
      "different_unit_footprint": "error",
      "different_unit_net": "error",
      "duplicate_reference": "error",
      "duplicate_sheet_names": "error",
      "endpoint_off_grid": "warning",
      "extra_units": "error",
      "footprint_filter": "ignore",
      "footprint_link_issues": "warning",
      "four_way_junction": "ignore",
      "global_label_dangling": "warning",
      "hier_label_mismatch": "error",
      "label_dangling": "error",
      "label_multiple_wires": "warning",
      "lib_symbol_issues": "warning",
      "lib_symbol_mismatch": "warning",
      "missing_bidi_pin": "warning",
      "missing_input_pin": "warning",
      "missing_power_pin": "error",
      "missing_unit": "warning",
      "multiple_net_names": "warning",
      "net_not_bus_member": "warning",
      "no_connect_connected": "error",
      "no_connect_dangling": "warning",
      "pin_not_connected": "error",
      "pin_not_driven": "error",
      "pin_to_pin": "ignore",
      "power_pin_not_driven": "error",
      "same_local_global_label": "warning",
      "similar_label_and_power": "warning",
      "similar_labels": "warning",
      "similar_power": "warning",
      "simulation_model_issue": "ignore",
      "single_global_label": "ignore",
      "unannotated": "error",
      "unconnected_wire_endpoint": "warning",
      "unit_value_mismatch": "error",
      "unresolved_variable": "error",
      "wire_dangling": "error"
    }
  },
  "libraries": {
    "pinned_footprint_libs": [],
    "pinned_symbol_libs": []
  },
  "meta": {
    "filename": "polarfire-som.kicad_pro",
    "version": 3
  },
  "net_settings": {
    "classes": [
      {
        "bus_width": 12,
        "clearance": 0.09,
        "diff_pair_gap": 0.1,
        "diff_pair_via_gap": 0.25,
        "diff_pair_width": 0.1,
        "line_style": 0,
        "microvia_diameter": 0.3,
        "microvia_drill": 0.1,
        "name": "Default",
        "pcb_color": "rgba(0, 0, 0, 0.000)",
        "priority": 2147483647,
        "schematic_color": "rgba(0, 0, 0, 0.000)",
        "track_width": 0.09,
        "via_diameter": 0.45,
        "via_drill": 0.1,
        "wire_width": 6
      },
      {
        "bus_width": 12,
        "clearance": 0.09,
        "diff_pair_gap": 0.1,
        "diff_pair_width": 0.1,
        "line_style": 0,
        "microvia_diameter": 0.3,
        "microvia_drill": 0.1,
        "name": "100Ohm-diff",
        "pcb_color": "rgb(62, 35, 255)",
        "priority": 0,
        "schematic_color": "rgba(0, 0, 0, 0.000)",
        "track_width": 0.1,
        "via_diameter": 0.45,
        "via_drill": 0.1,
        "wire_width": 6
      },
      {
        "bus_width": 12,
        "clearance": 0.09,
        "diff_pair_gap": 0.1,
        "diff_pair_width": 0.1,
        "line_style": 0,
        "microvia_diameter": 0.3,
        "microvia_drill": 0.1,
        "name": "40Ohm-se_DQ",
        "pcb_color": "rgba(0, 0, 0, 0.000)",
        "priority": 1,
        "schematic_color": "rgba(0, 0, 0, 0.000)",
        "track_width": 0.1,
        "via_diameter": 0.45,
        "via_drill": 0.1,
        "wire_width": 6
      },
      {
        "bus_width": 12,
        "clearance": 0.09,
        "diff_pair_gap": 0.1,
        "diff_pair_width": 0.1,
        "line_style": 0,
        "microvia_diameter": 0.3,
        "microvia_drill": 0.1,
        "name": "50Ohm-se",
        "pcb_color": "rgba(0, 0, 0, 0.000)",
        "priority": 2,
        "schematic_color": "rgba(0, 0, 0, 0.000)",
        "track_width": 0.1,
        "via_diameter": 0.45,
        "via_drill": 0.1,
        "wire_width": 6
      },
      {
        "bus_width": 12,
        "clearance": 0.09,
        "diff_pair_gap": 0.1,
        "diff_pair_width": 0.1,
        "line_style": 0,
        "microvia_diameter": 0.3,
        "microvia_drill": 0.1,
        "name": "80Ohm-diff_DQS",
        "pcb_color": "rgba(0, 0, 0, 0.000)",
        "priority": 3,
        "schematic_color": "rgba(0, 0, 0, 0.000)",
        "track_width": 0.1,
        "via_diameter": 0.45,
        "via_drill": 0.1,
        "wire_width": 6
      },
      {
        "bus_width": 12,
        "clearance": 0.09,
        "diff_pair_gap": 0.1,
        "diff_pair_width": 0.1,
        "line_style": 0,
        "microvia_diameter": 0.3,
        "microvia_drill": 0.1,
        "name": "85Ohm-diff_PCIe",
        "pcb_color": "rgba(0, 0, 0, 0.000)",
        "priority": 4,
        "schematic_color": "rgba(0, 0, 0, 0.000)",
        "track_width": 0.1,
        "via_diameter": 0.45,
        "via_drill": 0.1,
        "wire_width": 6
      },
      {
        "bus_width": 12,
        "clearance": 0.09,
        "diff_pair_gap": 0.1,
        "diff_pair_width": 0.1,
        "line_style": 0,
        "microvia_diameter": 0.3,
        "microvia_drill": 0.1,
        "name": "90Ohm-diff",
        "pcb_color": "rgba(0, 0, 0, 0.000)",
        "priority": 5,
        "schematic_color": "rgba(0, 0, 0, 0.000)",
        "track_width": 0.1,
        "via_diameter": 0.45,
        "via_drill": 0.1,
        "wire_width": 6
      },
      {
        "bus_width": 12,
        "clearance": 0.26,
        "diff_pair_gap": 0.1,
        "diff_pair_width": 0.1,
        "line_style": 0,
        "microvia_diameter": 0.3,
        "microvia_drill": 0.1,
        "name": "POE",
        "pcb_color": "rgba(0, 0, 0, 0.000)",
        "priority": 6,
        "schematic_color": "rgba(0, 0, 0, 0.000)",
        "track_width": 0.1,
        "via_diameter": 0.45,
        "via_drill": 0.1,
        "wire_width": 6
      },
      {
        "bus_width": 12,
        "clearance": 0.1,
        "diff_pair_gap": 0.25,
        "diff_pair_width": 0.2,
        "line_style": 0,
        "microvia_diameter": 0.3,
        "microvia_drill": 0.1,
        "name": "Supply",
        "pcb_color": "rgba(0, 0, 0, 0.000)",
        "priority": 7,
        "schematic_color": "rgba(0, 0, 0, 0.000)",
        "track_width": 0.4,
        "via_diameter": 0.45,
        "via_drill": 0.1,
        "wire_width": 6
      }
    ],
    "meta": {
      "version": 4
    },
    "net_colors": null,
    "netclass_assignments": null,
    "netclass_patterns": [
      {
        "netclass": "100Ohm-diff",
        "pattern": "*ETH.TXRX*"
      },
      {
        "netclass": "50Ohm-se",
        "pattern": "*ETH_M*"
      },
      {
        "netclass": "50Ohm-se",
        "pattern": "*ULPI.DATA*"
      },
      {
        "netclass": "90Ohm-diff",
        "pattern": "*USB_CLK"
      },
      {
        "netclass": "90Ohm-diff",
        "pattern": "*USB_BYP*"
      },
      {
        "netclass": "90Ohm-diff",
        "pattern": "*USB_UP*"
      },
      {
        "netclass": "90Ohm-diff",
        "pattern": "*USB_DN*"
      },
      {
        "netclass": "90Ohm-diff",
        "pattern": "*CAM*"
      },
      {
        "netclass": "90Ohm-diff",
        "pattern": "*DSI*"
      },
      {
        "netclass": "85Ohm-diff_PCIe",
        "pattern": "*PF_PCIe_CLK*"
      },
      {
        "netclass": "85Ohm-diff_PCIe",
        "pattern": "*PCIE.TX*"
      },
      {
        "netclass": "85Ohm-diff_PCIe",
        "pattern": "*PCIE.RX*"
      },
      {
        "netclass": "100Ohm-diff",
        "pattern": "*HDMI0.TX*"
      },
      {
        "netclass": "100Ohm-diff",
        "pattern": "*HDMI0.CLK*"
      },
      {
        "netclass": "50Ohm-se",
        "pattern": "*Crosslink_D*"
      },
      {
        "netclass": "100Ohm-diff",
        "pattern": "*PI3HDX511F_TX*"
      },
      {
        "netclass": "100Ohm-diff",
        "pattern": "*PI3HDX511F_CLK*"
      },
      {
        "netclass": "100Ohm-diff",
        "pattern": "*/SGMII*"
      },
      {
        "netclass": "50Ohm-se",
        "pattern": "*SDIO*"
      },
      {
        "netclass": "50Ohm-se",
        "pattern": "*EMMC.*"
      },
      {
        "netclass": "50Ohm-se",
        "pattern": "*SD.DAT*"
      },
      {
        "netclass": "50Ohm-se",
        "pattern": "*MEM.*"
      },
      {
        "netclass": "100Ohm-diff",
        "pattern": "*LPDDR4.DQS*"
      },
      {
        "netclass": "50Ohm-se",
        "pattern": "*LPDDR4.C*"
      },
      {
        "netclass": "50Ohm-se",
        "pattern": "*LPDDR4.???"
      },
      {
        "netclass": "50Ohm-se",
        "pattern": "*LPDDR4.????"
      },
      {
        "netclass": "50Ohm-se",
        "pattern": "*LPDDR4.RESET_n"
      },
      {
        "netclass": "50Ohm-se",
        "pattern": "*LPDDR4.ODT_CA_A"
      },
      {
        "netclass": "100Ohm-diff",
        "pattern": "*/PI3HDX*"
      },
      {
        "netclass": "90Ohm-diff",
        "pattern": "*USB_?"
      },
      {
        "netclass": "85Ohm-diff_PCIe",
        "pattern": "*XCVR_TX*"
      },
      {
        "netclass": "50Ohm-se",
        "pattern": "SD_CMD"
      },
      {
        "netclass": "50Ohm-se",
        "pattern": "SD_CLK"
      },
      {
        "netclass": "100Ohm-diff",
        "pattern": "*MSS_CLK*"
      },
      {
        "netclass": "100Ohm-diff",
        "pattern": "*HDMI_FPGA*_P"
      },
      {
        "netclass": "100Ohm-diff",
        "pattern": "*HDMI_FPGA*_N"
      }
    ]
  },
  "pcbnew": {
    "last_paths": {
      "gencad": "",
      "idf": "",
      "netlist": "",
      "plot": "",
      "pos_files": "",
      "specctra_dsn": "",
      "step": "",
      "svg": "",
      "vrml": ""
    },
    "page_layout_descr_file": ""
  },
  "schematic": {
    "annotate_start_num": 0,
    "bom_export_filename": "",
    "bom_fmt_presets": [],
    "bom_fmt_settings": {
      "field_delimiter": ",",
      "keep_line_breaks": false,
      "keep_tabs": false,
      "name": "CSV",
      "ref_delimiter": ",",
      "ref_range_delimiter": "",
      "string_delimiter": "\""
    },
    "bom_presets": [],
    "bom_settings": {
      "exclude_dnp": false,
      "fields_ordered": [
        {
          "group_by": false,
          "label": "Reference",
          "name": "Reference",
          "show": true
        },
        {
          "group_by": true,
          "label": "Value",
          "name": "Value",
          "show": true
        },
        {
          "group_by": false,
          "label": "Datasheet",
          "name": "Datasheet",
          "show": true
        },
        {
          "group_by": false,
          "label": "Footprint",
          "name": "Footprint",
          "show": true
        },
        {
          "group_by": false,
          "label": "Qty",
          "name": "${QUANTITY}",
          "show": true
        },
        {
          "group_by": true,
          "label": "DNP",
          "name": "${DNP}",
          "show": true
        }
      ],
      "filter_string": "",
      "group_symbols": true,
      "include_excluded_from_bom": false,
      "name": "Grouped By Value",
      "sort_asc": true,
      "sort_field": "Reference"
    },
    "connection_grid_size": 50.0,
    "drawing": {
      "dashed_lines_dash_length_ratio": 12.0,
      "dashed_lines_gap_length_ratio": 3.0,
      "default_line_thickness": 6.0,
      "default_text_size": 50.0,
      "field_names": [],
      "intersheets_ref_own_page": false,
      "intersheets_ref_prefix": "Pg. ",
      "intersheets_ref_short": false,
      "intersheets_ref_show": true,
      "intersheets_ref_suffix": "",
      "junction_size_choice": 3,
      "label_size_ratio": 0.375,
      "operating_point_overlay_i_precision": 3,
      "operating_point_overlay_i_range": "~A",
      "operating_point_overlay_v_precision": 3,
      "operating_point_overlay_v_range": "~V",
      "overbar_offset_ratio": 1.23,
      "pin_symbol_size": 25.0,
      "text_offset_ratio": 0.15
    },
    "legacy_lib_dir": "",
    "legacy_lib_list": [],
    "meta": {
      "version": 1
    },
    "net_format_name": "",
    "ngspice": {
      "fix_include_paths": true,
      "fix_passive_vals": false,
      "meta": {
        "version": 0
      },
      "model_mode": 0,
      "workbook_filename": ""
    },
    "page_layout_descr_file": "",
    "plot_directory": "",
    "space_save_all_events": true,
    "spice_adjust_passive_values": false,
    "spice_current_sheet_as_root": false,
    "spice_external_command": "spice \"%I\"",
    "spice_model_current_sheet_as_root": true,
    "spice_save_all_currents": false,
    "spice_save_all_dissipations": false,
    "spice_save_all_voltages": false,
    "subpart_first_id": 65,
    "subpart_id_separator": 0
  },
  "sheets": [
    [
      "",
      "Root"
    ],
    [
      "",
      "FPGA Config"
    ],
    [
      "",
      "FPGA Supply"
    ],
    [
      "",
      "Memory"
    ],
    [
      "",
      "Supply"
    ],
    [
      "",
      "LPDDR4"
    ],
    [
      "",
      "USB"
    ],
    [
      "",
      "PCIe"
    ],
    [
      "",
      "MIPI CrossLink"
    ],
    [
      "",
      "HDMI"
    ],
    [
      "",
      "Ethernet"
    ],
    [
      "",
      "Bottom Connector"
    ],
    [
      "",
      "Top Connector"
    ],
    [
      "",
      "WiFi_Bluetooth"
    ],
    [
      "",
      "FPGA MSS"
    ],
    [
      "",
      "FPGA MSSIO"
    ],
    [
      "",
      "FPGA GPIO"
    ],
    [
      "",
      "FPGA HSIO"
    ]
  ],
  "text_variables": {}
}
